# SCM (Grand Teton) — schematic netlist excerpt (pin names and nets, part order shuffled) for the footprints in the layout excerpt that follows; sources: Cadence DE-HDL packaged netlist, KiCad conversion of 12092022_DA0F0TMDCD0_F0T_Management_Board_D_brd_V3_OCP.brd

R420  Q_RES  150 1% CHIP  pkg 0402LF  page 26 : A = SMB_BMC_MM16_R2_SCL ; B = SMB_BMC_MM16_SCL
C35  Q_CAP  1UF 25V 10% X6S  pkg C0402  page 15 : A = P3V3_P1V8_SD1VDD ; B = GND

(kicad_pcb
	(version 20260206)
	(generator "pcbnew")
	(generator_version "10.0")
	(general
		(thickness 1.6)
		(legacy_teardrops no)
	)
	(paper "A4")
	(title_block
		(title "12092022_DA0F0TMDCD0_F0T_Management_Board_D_brd_V3_OCP.brd")
		(comment 1 "Grand Teton / footprints 1143-1144 of 1440")
	)
	(layers
		(0 "F.Cu" signal "TOP")
		(4 "In1.Cu" signal "GND")
		(6 "In2.Cu" signal "IN1")
		(8 "In3.Cu" signal "GND1")
		(10 "In4.Cu" signal "IN2")
		(12 "In5.Cu" signal "VCC")
		(14 "In6.Cu" signal "VCC1")
		(16 "In7.Cu" signal "IN3")
		(18 "In8.Cu" signal "GND2")
		(20 "In9.Cu" signal "IN4")
		(22 "In10.Cu" signal "GND3")
		(2 "B.Cu" signal "BOTTOM")
		(9 "F.Adhes" user "F.Adhesive")
		(11 "B.Adhes" user "B.Adhesive")
		(13 "F.Paste" user "Package Geometry/Pastemask Top")
		(15 "B.Paste" user "Package Geometry/Pastemask Bottom")
		(5 "F.SilkS" user "Ref Des/Silkscreen Top")
		(7 "B.SilkS" user "Ref Des/Silkscreen Bottom")
		(1 "F.Mask" user "Board Geometry/Soldermask Top")
		(3 "B.Mask" user "Board Geometry/Soldermask Bottom")
		(17 "Dwgs.User" user "User.Drawings")
		(19 "Cmts.User" user "User.Comments")
		(21 "Eco1.User" user "User.Eco1")
		(23 "Eco2.User" user "User.Eco2")
		(25 "Edge.Cuts" user "Board Geometry/Outline")
		(27 "Margin" user)
		(31 "F.CrtYd" user "Package Geometry/Place Bound Top")
		(29 "B.CrtYd" user "Package Geometry/Place Bound Bottom")
		(35 "F.Fab" user "Ref Des/Assembly Top")
		(33 "B.Fab" user "Ref Des/Assembly Bottom")
	)
	(footprint ""
		(layer "B.Cu")
		(at 68.608448 -27.489404 180)
		(property "Reference" "R420"
			(at 0 0 0)
			(layer "B.SilkS")
			(hide yes)
			(effects
				(font
					(size 1.27 1.27)
				)
				(justify mirror)
			)
		)
		(property "Value" ""
			(at 0 0 0)
			(layer "B.Fab")
			(effects
				(font
					(size 1.27 1.27)
				)
				(justify mirror)
			)
		)
		(duplicate_pad_numbers_are_jumpers no)
		(fp_line
			(start 0.7874 0.4064)
			(end 0.7874 -0.4064)
			(stroke
				(width 0.1524)
				(type default)
			)
			(layer "B.SilkS")
		)
		(fp_line
			(start 0.7874 -0.4064)
			(end -0.7874 -0.4064)
			(stroke
				(width 0.1524)
				(type default)
			)
			(layer "B.SilkS")
		)
		(fp_line
			(start -0.7874 0.4064)
			(end 0.7874 0.4064)
			(stroke
				(width 0.1524)
				(type default)
			)
			(layer "B.SilkS")
		)
		(fp_line
			(start -0.7874 -0.4064)
			(end -0.7874 0.4064)
			(stroke
				(width 0.1524)
				(type default)
			)
			(layer "B.SilkS")
		)
		(fp_line
			(start 0.67945 0.3048)
			(end 0.67945 -0.305054)
			(stroke
				(width 0.1)
				(type default)
			)
			(layer "B.Fab")
		)
		(fp_line
			(start 0.67945 -0.305054)
			(end 0.12065 -0.305054)
			(stroke
				(width 0.1)
				(type default)
			)
			(layer "B.Fab")
		)
		(fp_line
			(start 0.12065 0.3048)
			(end 0.67945 0.3048)
			(stroke
				(width 0.1)
				(type default)
			)
			(layer "B.Fab")
		)
		(fp_line
			(start 0.12065 0.2794)
			(end 0.12065 0.3048)
			(stroke
				(width 0.1)
				(type default)
			)
			(layer "B.Fab")
		)
		(fp_line
			(start 0.12065 -0.2794)
			(end -0.12065 -0.2794)
			(stroke
				(width 0.1)
				(type default)
			)
			(layer "B.Fab")
		)
		(fp_line
			(start 0.12065 -0.305054)
			(end 0.12065 -0.2794)
			(stroke
				(width 0.1)
				(type default)
			)
			(layer "B.Fab")
		)
		(fp_line
			(start -0.120396 0.3048)
			(end -0.120396 0.2794)
			(stroke
				(width 0.1)
				(type default)
			)
			(layer "B.Fab")
		)
		(fp_line
			(start -0.120396 0.2794)
			(end 0.12065 0.2794)
			(stroke
				(width 0.1)
				(type default)
			)
			(layer "B.Fab")
		)
		(fp_line
			(start -0.12065 -0.2794)
			(end -0.12065 -0.3048)
			(stroke
				(width 0.1)
				(type default)
			)
			(layer "B.Fab")
		)
		(fp_line
			(start -0.12065 -0.3048)
			(end -0.67945 -0.3048)
			(stroke
				(width 0.1)
				(type default)
			)
			(layer "B.Fab")
		)
		(fp_line
			(start -0.67945 0.3048)
			(end -0.120396 0.3048)
			(stroke
				(width 0.1)
				(type default)
			)
			(layer "B.Fab")
		)
		(fp_line
			(start -0.67945 -0.3048)
			(end -0.67945 0.3048)
			(stroke
				(width 0.1)
				(type default)
			)
			(layer "B.Fab")
		)
		(pad "1" smd circle
			(at 0.40005 0)
			(size 0 0)
			(layers "B.Cu" "B.Mask" "B.Paste")
			(net "SMB_BMC_MM16_R2_SCL")
		)
		(pad "2" smd circle
			(at -0.40005 0)
			(size 0 0)
			(layers "B.Cu" "B.Mask" "B.Paste")
			(net "SMB_BMC_MM16_SCL")
		)
	)
	(footprint ""
		(layer "B.Cu")
		(at 39.75735 -38.532308 -90)
		(property "Reference" "C35"
			(at 0 0 90)
			(layer "B.SilkS")
			(hide yes)
			(effects
				(font
					(size 1.27 1.27)
				)
				(justify mirror)
			)
		)
		(property "Value" ""
			(at 0 0 90)
			(layer "B.Fab")
			(effects
				(font
					(size 1.27 1.27)
				)
				(justify mirror)
			)
		)
		(duplicate_pad_numbers_are_jumpers no)
		(fp_line
			(start -0.7874 0.4064)
			(end 0.7874 0.4064)
			(stroke
				(width 0.1524)
				(type default)
			)
			(layer "B.SilkS")
		)
		(fp_line
			(start 0.7874 0.4064)
			(end 0.7874 -0.4064)
			(stroke
				(width 0.1524)
				(type default)
			)
			(layer "B.SilkS")
		)
		(fp_line
			(start -0.7874 -0.4064)
			(end -0.7874 0.4064)
			(stroke
				(width 0.1524)
				(type default)
			)
			(layer "B.SilkS")
		)
		(fp_line
			(start 0.7874 -0.4064)
			(end -0.7874 -0.4064)
			(stroke
				(width 0.1524)
				(type default)
			)
			(layer "B.SilkS")
		)
		(fp_line
			(start -0.67945 0.3048)
			(end -0.120396 0.3048)
			(stroke
				(width 0.1)
				(type default)
			)
			(layer "B.Fab")
		)
		(fp_line
			(start -0.120396 0.3048)
			(end -0.120396 0.2794)
			(stroke
				(width 0.1)
				(type default)
			)
			(layer "B.Fab")
		)
		(fp_line
			(start 0.12065 0.3048)
			(end 0.67945 0.3048)
			(stroke
				(width 0.1)
				(type default)
			)
			(layer "B.Fab")
		)
		(fp_line
			(start 0.67945 0.3048)
			(end 0.67945 -0.305054)
			(stroke
				(width 0.1)
				(type default)
			)
			(layer "B.Fab")
		)
		(fp_line
			(start -0.120396 0.2794)
			(end 0.12065 0.2794)
			(stroke
				(width 0.1)
				(type default)
			)
			(layer "B.Fab")
		)
		(fp_line
			(start 0.12065 0.2794)
			(end 0.12065 0.3048)
			(stroke
				(width 0.1)
				(type default)
			)
			(layer "B.Fab")
		)
		(fp_line
			(start -0.12065 -0.2794)
			(end -0.12065 -0.3048)
			(stroke
				(width 0.1)
				(type default)
			)
			(layer "B.Fab")
		)
		(fp_line
			(start 0.12065 -0.2794)
			(end -0.12065 -0.2794)
			(stroke
				(width 0.1)
				(type default)
			)
			(layer "B.Fab")
		)
		(fp_line
			(start -0.67945 -0.3048)
			(end -0.67945 0.3048)
			(stroke
				(width 0.1)
				(type default)
			)
			(layer "B.Fab")
		)
		(fp_line
			(start -0.12065 -0.3048)
			(end -0.67945 -0.3048)
			(stroke
				(width 0.1)
				(type default)
			)
			(layer "B.Fab")
		)
		(fp_line
			(start 0.12065 -0.305054)
			(end 0.12065 -0.2794)
			(stroke
				(width 0.1)
				(type default)
			)
			(layer "B.Fab")
		)
		(fp_line
			(start 0.67945 -0.305054)
			(end 0.12065 -0.305054)
			(stroke
				(width 0.1)
				(type default)
			)
			(layer "B.Fab")
		)
		(pad "1" smd circle
			(at 0.40005 0 90)
			(size 0 0)
			(layers "B.Cu" "B.Mask" "B.Paste")
			(net "P3V3_P1V8_SD1VDD")
		)
		(pad "2" smd circle
			(at -0.40005 0 90)
			(size 0 0)
			(layers "B.Cu" "B.Mask" "B.Paste")
			(net "GND")
		)
	)
)
